# T6G (Grand Teton) — schematic netlist excerpt (pin names and nets, part order shuffled) for the footprints in the layout excerpt that follows; sources: Cadence DE-HDL packaged netlist, KiCad conversion of 04192023_DAF0TMB3IC0_F0TG_MB_C_brd_V02_OCP.brd

PR434  Q_RES  10 1% CHIP  pkg 0402LF  page 209 : A = PVDD18_S5_P0_FB_RC ; B = VSENSE_PVDD18_S5_P0_DP
PC6582_2  Q_CAP  22UF 16V 20% X6S  pkg C0805  page 363 : A = SW_P12V_AUX_P0V9_RETIMER_CPU0_FLT ; B = GND

(kicad_pcb
	(version 20260206)
	(generator "pcbnew")
	(generator_version "10.0")
	(general
		(thickness 1.6)
		(legacy_teardrops no)
	)
	(paper "A4")
	(title_block
		(title "04192023_DAF0TMB3IC0_F0TG_MB_C_brd_V02_OCP.brd")
		(comment 1 "Grand Teton / footprints 128-129 of 8354")
	)
	(layers
		(0 "F.Cu" signal "TOP")
		(4 "In1.Cu" signal "GND")
		(6 "In2.Cu" signal "IN1")
		(8 "In3.Cu" signal "GND1")
		(10 "In4.Cu" signal "IN2")
		(12 "In5.Cu" signal "GND2")
		(14 "In6.Cu" signal "IN3")
		(16 "In7.Cu" signal "GND3")
		(18 "In8.Cu" signal "VCC")
		(20 "In9.Cu" signal "VCC1")
		(22 "In10.Cu" signal "GND4")
		(24 "In11.Cu" signal "IN4")
		(26 "In12.Cu" signal "GND5")
		(28 "In13.Cu" signal "IN5")
		(30 "In14.Cu" signal "GND6")
		(32 "In15.Cu" signal "IN6")
		(34 "In16.Cu" signal "GND7")
		(2 "B.Cu" signal "BOTTOM")
		(9 "F.Adhes" user "F.Adhesive")
		(11 "B.Adhes" user "B.Adhesive")
		(13 "F.Paste" user "Package Geometry/Pastemask Top")
		(15 "B.Paste" user "Package Geometry/Pastemask Bottom")
		(5 "F.SilkS" user "Ref Des/Silkscreen Top")
		(7 "B.SilkS" user "Ref Des/Silkscreen Bottom")
		(1 "F.Mask" user "Board Geometry/Soldermask Top")
		(3 "B.Mask" user "Board Geometry/Soldermask Bottom")
		(17 "Dwgs.User" user "User.Drawings")
		(19 "Cmts.User" user "User.Comments")
		(21 "Eco1.User" user "User.Eco1")
		(23 "Eco2.User" user "User.Eco2")
		(25 "Edge.Cuts" user "Board Geometry/Outline")
		(27 "Margin" user)
		(31 "F.CrtYd" user "Package Geometry/Place Bound Top")
		(29 "B.CrtYd" user "Package Geometry/Place Bound Bottom")
		(35 "F.Fab" user "Ref Des/Assembly Top")
		(33 "B.Fab" user "Ref Des/Assembly Bottom")
	)
	(footprint ""
		(layer "F.Cu")
		(at 328.367644 -138.893042 -90)
		(property "Reference" "PR434"
			(at 0 0 270)
			(layer "F.SilkS")
			(hide yes)
			(effects
				(font
					(size 1.27 1.27)
				)
			)
		)
		(property "Value" ""
			(at 0 0 270)
			(layer "F.Fab")
			(effects
				(font
					(size 1.27 1.27)
				)
			)
		)
		(duplicate_pad_numbers_are_jumpers no)
		(fp_line
			(start -0.7874 0.4064)
			(end -0.7874 -0.4064)
			(stroke
				(width 0.1524)
				(type default)
			)
			(layer "F.SilkS")
		)
		(fp_line
			(start 0.7874 0.4064)
			(end -0.7874 0.4064)
			(stroke
				(width 0.1524)
				(type default)
			)
			(layer "F.SilkS")
		)
		(fp_line
			(start -0.7874 -0.4064)
			(end 0.7874 -0.4064)
			(stroke
				(width 0.1524)
				(type default)
			)
			(layer "F.SilkS")
		)
		(fp_line
			(start 0.7874 -0.4064)
			(end 0.7874 0.4064)
			(stroke
				(width 0.1524)
				(type default)
			)
			(layer "F.SilkS")
		)
		(fp_line
			(start -0.67945 0.3048)
			(end -0.67945 -0.305054)
			(stroke
				(width 0.1)
				(type default)
			)
			(layer "F.Fab")
		)
		(fp_line
			(start -0.12065 0.3048)
			(end -0.67945 0.3048)
			(stroke
				(width 0.1)
				(type default)
			)
			(layer "F.Fab")
		)
		(fp_line
			(start 0.120396 0.3048)
			(end 0.120396 0.2794)
			(stroke
				(width 0.1)
				(type default)
			)
			(layer "F.Fab")
		)
		(fp_line
			(start 0.67945 0.3048)
			(end 0.120396 0.3048)
			(stroke
				(width 0.1)
				(type default)
			)
			(layer "F.Fab")
		)
		(fp_line
			(start -0.12065 0.2794)
			(end -0.12065 0.3048)
			(stroke
				(width 0.1)
				(type default)
			)
			(layer "F.Fab")
		)
		(fp_line
			(start 0.120396 0.2794)
			(end -0.12065 0.2794)
			(stroke
				(width 0.1)
				(type default)
			)
			(layer "F.Fab")
		)
		(fp_line
			(start -0.12065 -0.2794)
			(end 0.12065 -0.2794)
			(stroke
				(width 0.1)
				(type default)
			)
			(layer "F.Fab")
		)
		(fp_line
			(start 0.12065 -0.2794)
			(end 0.12065 -0.3048)
			(stroke
				(width 0.1)
				(type default)
			)
			(layer "F.Fab")
		)
		(fp_line
			(start 0.12065 -0.3048)
			(end 0.67945 -0.3048)
			(stroke
				(width 0.1)
				(type default)
			)
			(layer "F.Fab")
		)
		(fp_line
			(start 0.67945 -0.3048)
			(end 0.67945 0.3048)
			(stroke
				(width 0.1)
				(type default)
			)
			(layer "F.Fab")
		)
		(fp_line
			(start -0.67945 -0.305054)
			(end -0.12065 -0.305054)
			(stroke
				(width 0.1)
				(type default)
			)
			(layer "F.Fab")
		)
		(fp_line
			(start -0.12065 -0.305054)
			(end -0.12065 -0.2794)
			(stroke
				(width 0.1)
				(type default)
			)
			(layer "F.Fab")
		)
		(pad "1" smd circle
			(at -0.40005 0 270)
			(size 0 0)
			(layers "F.Cu" "F.Mask" "F.Paste")
			(net "PVDD18_S5_P0_FB_RC")
		)
		(pad "2" smd circle
			(at 0.40005 0 270)
			(size 0 0)
			(layers "F.Cu" "F.Mask" "F.Paste")
			(net "VSENSE_PVDD18_S5_P0_DP")
		)
	)
	(footprint ""
		(layer "F.Cu")
		(at 458.346302 -407.877264)
		(property "Reference" "PC6582_2"
			(at 0 0 0)
			(layer "F.SilkS")
			(hide yes)
			(effects
				(font
					(size 1.27 1.27)
				)
			)
		)
		(property "Value" ""
			(at 0 0 0)
			(layer "F.Fab")
			(effects
				(font
					(size 1.27 1.27)
				)
			)
		)
		(duplicate_pad_numbers_are_jumpers no)
		(fp_line
			(start -1.524 -0.762)
			(end 1.524 -0.762)
			(stroke
				(width 0.1524)
				(type default)
			)
			(layer "F.SilkS")
		)
		(fp_line
			(start -1.524 0.762)
			(end -1.524 -0.762)
			(stroke
				(width 0.1524)
				(type default)
			)
			(layer "F.SilkS")
		)
		(fp_line
			(start 1.524 -0.762)
			(end 1.524 0.762)
			(stroke
				(width 0.1524)
				(type default)
			)
			(layer "F.SilkS")
		)
		(fp_line
			(start 1.524 0.762)
			(end -1.524 0.762)
			(stroke
				(width 0.1524)
				(type default)
			)
			(layer "F.SilkS")
		)
		(fp_line
			(start -1.1049 -0.724916)
			(end -1.1049 0.724916)
			(stroke
				(width 0.1)
				(type default)
			)
			(layer "F.Fab")
		)
		(fp_line
			(start -1.1049 0.724916)
			(end 1.1049 0.724916)
			(stroke
				(width 0.1)
				(type default)
			)
			(layer "F.Fab")
		)
		(fp_line
			(start 1.1049 -0.724916)
			(end -1.1049 -0.724916)
			(stroke
				(width 0.1)
				(type default)
			)
			(layer "F.Fab")
		)
		(fp_line
			(start 1.1049 0.724916)
			(end 1.1049 -0.724916)
			(stroke
				(width 0.1)
				(type default)
			)
			(layer "F.Fab")
		)
		(pad "1" smd rect
			(at -0.889 0 180)
			(size 1.016 1.27)
			(layers "F.Cu" "F.Mask" "F.Paste")
			(net "SW_P12V_AUX_P0V9_RETIMER_CPU0_FLT")
		)
		(pad "2" smd rect
			(at 0.889 0 180)
			(size 1.016 1.27)
			(layers "F.Cu" "F.Mask" "F.Paste")
			(net "GND")
		)
	)
)
